# T6G (Grand Teton) — schematic netlist excerpt (pin names and nets, part order shuffled) for the footprints in the layout excerpt that follows; sources: Cadence DE-HDL packaged netlist, KiCad conversion of 04192023_DAF0TMB3IC0_F0TG_MB_C_brd_V02_OCP.brd

PC128_6  Q_CAP  1UF 25V 10% X6S  pkg C0402  page 213 : A = SW_P12V_AUX_PVDDCR_CPU0_P1_FLT ; B = GND

X9008  TP_TDR_4P_FTS  TP_TDR_4P_DIP EMPTY  pkg TH  page 261
  S1  = TDR_DIFF_85_NECK_IN1_DN
  P1  = T1_GND
  P2  = T1_GND
  S2  = TDR_DIFF_85_NECK_IN1_DP

(kicad_pcb
	(version 20260206)
	(generator "pcbnew")
	(generator_version "10.0")
	(general
		(thickness 1.6)
		(legacy_teardrops no)
	)
	(paper "A4")
	(title_block
		(title "04192023_DAF0TMB3IC0_F0TG_MB_C_brd_V02_OCP.brd")
		(comment 1 "Grand Teton / footprints 4498-4499 of 8354")
	)
	(layers
		(0 "F.Cu" signal "TOP")
		(4 "In1.Cu" signal "GND")
		(6 "In2.Cu" signal "IN1")
		(8 "In3.Cu" signal "GND1")
		(10 "In4.Cu" signal "IN2")
		(12 "In5.Cu" signal "GND2")
		(14 "In6.Cu" signal "IN3")
		(16 "In7.Cu" signal "GND3")
		(18 "In8.Cu" signal "VCC")
		(20 "In9.Cu" signal "VCC1")
		(22 "In10.Cu" signal "GND4")
		(24 "In11.Cu" signal "IN4")
		(26 "In12.Cu" signal "GND5")
		(28 "In13.Cu" signal "IN5")
		(30 "In14.Cu" signal "GND6")
		(32 "In15.Cu" signal "IN6")
		(34 "In16.Cu" signal "GND7")
		(2 "B.Cu" signal "BOTTOM")
		(9 "F.Adhes" user "F.Adhesive")
		(11 "B.Adhes" user "B.Adhesive")
		(13 "F.Paste" user "Package Geometry/Pastemask Top")
		(15 "B.Paste" user "Package Geometry/Pastemask Bottom")
		(5 "F.SilkS" user "Ref Des/Silkscreen Top")
		(7 "B.SilkS" user "Ref Des/Silkscreen Bottom")
		(1 "F.Mask" user "Board Geometry/Soldermask Top")
		(3 "B.Mask" user "Board Geometry/Soldermask Bottom")
		(17 "Dwgs.User" user "User.Drawings")
		(19 "Cmts.User" user "User.Comments")
		(21 "Eco1.User" user "User.Eco1")
		(23 "Eco2.User" user "User.Eco2")
		(25 "Edge.Cuts" user "Board Geometry/Outline")
		(27 "Margin" user)
		(31 "F.CrtYd" user "Package Geometry/Place Bound Top")
		(29 "B.CrtYd" user "Package Geometry/Place Bound Bottom")
		(35 "F.Fab" user "Ref Des/Assembly Top")
		(33 "B.Fab" user "Ref Des/Assembly Bottom")
	)
	(footprint ""
		(layer "F.Cu")
		(at 503.645424 -457.3397 90)
		(property "Reference" "X9008"
			(at -2.017268 1.17475 0)
			(unlocked yes)
			(layer "F.SilkS")
			(effects
				(font
					(size 0.7874 0.5842)
					(thickness 0.1524)
				)
				(justify left)
			)
		)
		(property "Value" ""
			(at 0 0 90)
			(layer "F.Fab")
			(effects
				(font
					(size 1.27 1.27)
				)
			)
		)
		(property "User Part Number" "N_A"
			(at 1.30175 1.27 180)
			(unlocked yes)
			(layer "Cmts.User")
			(hide yes)
			(effects
				(font
					(size 0.635 0.4064)
					(thickness 0.1524)
				)
			)
		)
		(property "Device Type" "TP_TDR_4P_FTS_TH-TP_TDR_4P_DIP,EMPTY,TP15"
			(at 1.30175 1.27 180)
			(unlocked yes)
			(layer "F.Fab")
			(hide yes)
			(effects
				(font
					(size 0.635 0.4064)
					(thickness 0.1524)
				)
			)
		)
		(duplicate_pad_numbers_are_jumpers no)
		(fp_line
			(start 2.54 -1.27)
			(end 0 -1.27)
			(stroke
				(width 0.1524)
				(type default)
			)
			(layer "F.SilkS")
		)
		(fp_line
			(start 0 -1.27)
			(end 0 -0.635)
			(stroke
				(width 0.1524)
				(type default)
			)
			(layer "F.SilkS")
		)
		(fp_line
			(start 2.54 -1.1303)
			(end 2.54 -1.27)
			(stroke
				(width 0.1524)
				(type default)
			)
			(layer "F.SilkS")
		)
		(fp_line
			(start 0 0.635)
			(end 0 1.905)
			(stroke
				(width 0.1524)
				(type default)
			)
			(layer "F.SilkS")
		)
		(fp_line
			(start 2.54 1.4097)
			(end 2.54 1.1303)
			(stroke
				(width 0.1524)
				(type default)
			)
			(layer "F.SilkS")
		)
		(fp_line
			(start 0 3.175)
			(end 0 3.81)
			(stroke
				(width 0.1524)
				(type default)
			)
			(layer "F.SilkS")
		)
		(fp_line
			(start 2.54 3.81)
			(end 2.54 3.6703)
			(stroke
				(width 0.1524)
				(type default)
			)
			(layer "F.SilkS")
		)
		(fp_line
			(start 0 3.81)
			(end 2.54 3.81)
			(stroke
				(width 0.1524)
				(type default)
			)
			(layer "F.SilkS")
		)
		(fp_poly
			(pts
				(xy -2.285746 -0.762) (xy -0.761746 0) (xy -2.285746 0.762)
			)
			(stroke
				(width 0)
				(type default)
			)
			(fill yes)
			(layer "F.SilkS")
		)
		(fp_line
			(start 2.54 -1.27)
			(end 0 -1.27)
			(stroke
				(width 0.1)
				(type default)
			)
			(layer "F.Fab")
		)
		(fp_line
			(start 0 -1.27)
			(end 0 3.81)
			(stroke
				(width 0.1)
				(type default)
			)
			(layer "F.Fab")
		)
		(fp_line
			(start 2.54 3.81)
			(end 2.54 -1.27)
			(stroke
				(width 0.1)
				(type default)
			)
			(layer "F.Fab")
		)
		(fp_line
			(start 0 3.81)
			(end 2.54 3.81)
			(stroke
				(width 0.1)
				(type default)
			)
			(layer "F.Fab")
		)
		(fp_poly
			(pts
				(xy -0.761746 0) (xy -2.285746 -0.762) (xy -2.285746 0.762)
			)
			(stroke
				(width 0)
				(type default)
			)
			(fill yes)
			(layer "F.Fab")
		)
		(pad "1" thru_hole circle
			(at 0 0 90)
			(size 1.0033 1.0033)
			(drill 0.249936)
			(layers "*.Cu" "*.Mask")
			(remove_unused_layers no)
			(net "TDR_DIFF_85_NECK_IN1_DN")
			(clearance 0.10795)
			(thermal_gap 0.10795)
			(padstack
				(mode front_inner_back)
				(layer "Inner"
					(shape circle)
					(size 0.8001 0.8001)
					(clearance 0.1524)
				)
				(layer "B.Cu"
					(shape circle)
					(size 1.0033 1.0033)
					(clearance 0.10795)
				)
			)
		)
		(pad "2" thru_hole circle
			(at 2.54 0 90)
			(size 1.9939 1.9939)
			(drill 0.249936)
			(layers "*.Cu" "*.Mask")
			(remove_unused_layers no)
			(net "T1_GND")
			(clearance 0.10795)
			(thermal_gap 0.10795)
			(padstack
				(mode front_inner_back)
				(layer "Inner"
					(shape circle)
					(size 0.8001 0.8001)
					(clearance 0.1524)
				)
				(layer "B.Cu"
					(shape circle)
					(size 1.9939 1.9939)
					(clearance 0.10795)
				)
			)
		)
		(pad "3" thru_hole circle
			(at 2.54 2.54 90)
			(size 1.9939 1.9939)
			(drill 0.249936)
			(layers "*.Cu" "*.Mask")
			(remove_unused_layers no)
			(net "T1_GND")
			(clearance 0.10795)
			(thermal_gap 0.10795)
			(padstack
				(mode front_inner_back)
				(layer "Inner"
					(shape circle)
					(size 0.8001 0.8001)
					(clearance 0.1524)
				)
				(layer "B.Cu"
					(shape circle)
					(size 1.9939 1.9939)
					(clearance 0.10795)
				)
			)
		)
		(pad "4" thru_hole circle
			(at 0 2.54 90)
			(size 1.0033 1.0033)
			(drill 0.249936)
			(layers "*.Cu" "*.Mask")
			(remove_unused_layers no)
			(net "TDR_DIFF_85_NECK_IN1_DP")
			(clearance 0.10795)
			(thermal_gap 0.10795)
			(padstack
				(mode front_inner_back)
				(layer "Inner"
					(shape circle)
					(size 0.8001 0.8001)
					(clearance 0.1524)
				)
				(layer "B.Cu"
					(shape circle)
					(size 1.0033 1.0033)
					(clearance 0.10795)
				)
			)
		)
	)
	(footprint ""
		(layer "F.Cu")
		(at 62.00775 -168.843452 90)
		(property "Reference" "PC128_6"
			(at 0 0 90)
			(layer "F.SilkS")
			(hide yes)
			(effects
				(font
					(size 1.27 1.27)
				)
			)
		)
		(property "Value" ""
			(at 0 0 90)
			(layer "F.Fab")
			(effects
				(font
					(size 1.27 1.27)
				)
			)
		)
		(duplicate_pad_numbers_are_jumpers no)
		(fp_line
			(start 0.7874 -0.4064)
			(end 0.7874 0.4064)
			(stroke
				(width 0.1524)
				(type default)
			)
			(layer "F.SilkS")
		)
		(fp_line
			(start -0.7874 -0.4064)
			(end 0.7874 -0.4064)
			(stroke
				(width 0.1524)
				(type default)
			)
			(layer "F.SilkS")
		)
		(fp_line
			(start 0.7874 0.4064)
			(end -0.7874 0.4064)
			(stroke
				(width 0.1524)
				(type default)
			)
			(layer "F.SilkS")
		)
		(fp_line
			(start -0.7874 0.4064)
			(end -0.7874 -0.4064)
			(stroke
				(width 0.1524)
				(type default)
			)
			(layer "F.SilkS")
		)
		(fp_line
			(start -0.12065 -0.305054)
			(end -0.12065 -0.2794)
			(stroke
				(width 0.1)
				(type default)
			)
			(layer "F.Fab")
		)
		(fp_line
			(start -0.67945 -0.305054)
			(end -0.12065 -0.305054)
			(stroke
				(width 0.1)
				(type default)
			)
			(layer "F.Fab")
		)
		(fp_line
			(start 0.67945 -0.3048)
			(end 0.67945 0.3048)
			(stroke
				(width 0.1)
				(type default)
			)
			(layer "F.Fab")
		)
		(fp_line
			(start 0.12065 -0.3048)
			(end 0.67945 -0.3048)
			(stroke
				(width 0.1)
				(type default)
			)
			(layer "F.Fab")
		)
		(fp_line
			(start 0.12065 -0.2794)
			(end 0.12065 -0.3048)
			(stroke
				(width 0.1)
				(type default)
			)
			(layer "F.Fab")
		)
		(fp_line
			(start -0.12065 -0.2794)
			(end 0.12065 -0.2794)
			(stroke
				(width 0.1)
				(type default)
			)
			(layer "F.Fab")
		)
		(fp_line
			(start 0.120396 0.2794)
			(end -0.12065 0.2794)
			(stroke
				(width 0.1)
				(type default)
			)
			(layer "F.Fab")
		)
		(fp_line
			(start -0.12065 0.2794)
			(end -0.12065 0.3048)
			(stroke
				(width 0.1)
				(type default)
			)
			(layer "F.Fab")
		)
		(fp_line
			(start 0.67945 0.3048)
			(end 0.120396 0.3048)
			(stroke
				(width 0.1)
				(type default)
			)
			(layer "F.Fab")
		)
		(fp_line
			(start 0.120396 0.3048)
			(end 0.120396 0.2794)
			(stroke
				(width 0.1)
				(type default)
			)
			(layer "F.Fab")
		)
		(fp_line
			(start -0.12065 0.3048)
			(end -0.67945 0.3048)
			(stroke
				(width 0.1)
				(type default)
			)
			(layer "F.Fab")
		)
		(fp_line
			(start -0.67945 0.3048)
			(end -0.67945 -0.305054)
			(stroke
				(width 0.1)
				(type default)
			)
			(layer "F.Fab")
		)
		(pad "1" smd circle
			(at -0.40005 0 90)
			(size 0 0)
			(layers "F.Cu" "F.Mask" "F.Paste")
			(net "SW_P12V_AUX_PVDDCR_CPU0_P1_FLT")
		)
		(pad "2" smd circle
			(at 0.40005 0 90)
			(size 0 0)
			(layers "F.Cu" "F.Mask" "F.Paste")
			(net "GND")
		)
	)
)
